# SCM (Grand Teton) — schematic netlist excerpt (pin names and nets, part order shuffled) for the footprints in the layout excerpt that follows; sources: Cadence DE-HDL packaged netlist, KiCad conversion of 12092022_DA0F0TMDCD0_F0T_Management_Board_D_brd_V3_OCP.brd

R77  Q_RES  1K 1% EMPTY  pkg 0402LF  page 11 : A = P3V3_AUX ; B = SGPIO_LD_0
R371  Q_RES  120 1% CHIP  pkg 0402LF  page 20 : A = M_BMC_DDR4_MBA0 ; B = P1V2_AUX

(kicad_pcb
	(version 20260206)
	(generator "pcbnew")
	(generator_version "10.0")
	(general
		(thickness 1.6)
		(legacy_teardrops no)
	)
	(paper "A4")
	(title_block
		(title "12092022_DA0F0TMDCD0_F0T_Management_Board_D_brd_V3_OCP.brd")
		(comment 1 "Grand Teton / footprints 1259-1260 of 1440")
	)
	(layers
		(0 "F.Cu" signal "TOP")
		(4 "In1.Cu" signal "GND")
		(6 "In2.Cu" signal "IN1")
		(8 "In3.Cu" signal "GND1")
		(10 "In4.Cu" signal "IN2")
		(12 "In5.Cu" signal "VCC")
		(14 "In6.Cu" signal "VCC1")
		(16 "In7.Cu" signal "IN3")
		(18 "In8.Cu" signal "GND2")
		(20 "In9.Cu" signal "IN4")
		(22 "In10.Cu" signal "GND3")
		(2 "B.Cu" signal "BOTTOM")
		(9 "F.Adhes" user "F.Adhesive")
		(11 "B.Adhes" user "B.Adhesive")
		(13 "F.Paste" user "Package Geometry/Pastemask Top")
		(15 "B.Paste" user "Package Geometry/Pastemask Bottom")
		(5 "F.SilkS" user "Ref Des/Silkscreen Top")
		(7 "B.SilkS" user "Ref Des/Silkscreen Bottom")
		(1 "F.Mask" user "Board Geometry/Soldermask Top")
		(3 "B.Mask" user "Board Geometry/Soldermask Bottom")
		(17 "Dwgs.User" user "User.Drawings")
		(19 "Cmts.User" user "User.Comments")
		(21 "Eco1.User" user "User.Eco1")
		(23 "Eco2.User" user "User.Eco2")
		(25 "Edge.Cuts" user "Board Geometry/Outline")
		(27 "Margin" user)
		(31 "F.CrtYd" user "Package Geometry/Place Bound Top")
		(29 "B.CrtYd" user "Package Geometry/Place Bound Bottom")
		(35 "F.Fab" user "Ref Des/Assembly Top")
		(33 "B.Fab" user "Ref Des/Assembly Bottom")
	)
	(footprint ""
		(layer "B.Cu")
		(at 79.739744 -37.559488 90)
		(property "Reference" "R371"
			(at 0 0 90)
			(layer "B.SilkS")
			(hide yes)
			(effects
				(font
					(size 1.27 1.27)
				)
				(justify mirror)
			)
		)
		(property "Value" ""
			(at 0 0 90)
			(layer "B.Fab")
			(effects
				(font
					(size 1.27 1.27)
				)
				(justify mirror)
			)
		)
		(duplicate_pad_numbers_are_jumpers no)
		(fp_line
			(start 0.7874 -0.4064)
			(end -0.7874 -0.4064)
			(stroke
				(width 0.1524)
				(type default)
			)
			(layer "B.SilkS")
		)
		(fp_line
			(start -0.7874 -0.4064)
			(end -0.7874 0.4064)
			(stroke
				(width 0.1524)
				(type default)
			)
			(layer "B.SilkS")
		)
		(fp_line
			(start 0.7874 0.4064)
			(end 0.7874 -0.4064)
			(stroke
				(width 0.1524)
				(type default)
			)
			(layer "B.SilkS")
		)
		(fp_line
			(start -0.7874 0.4064)
			(end 0.7874 0.4064)
			(stroke
				(width 0.1524)
				(type default)
			)
			(layer "B.SilkS")
		)
		(fp_line
			(start 0.67945 -0.305054)
			(end 0.12065 -0.305054)
			(stroke
				(width 0.1)
				(type default)
			)
			(layer "B.Fab")
		)
		(fp_line
			(start 0.12065 -0.305054)
			(end 0.12065 -0.2794)
			(stroke
				(width 0.1)
				(type default)
			)
			(layer "B.Fab")
		)
		(fp_line
			(start -0.12065 -0.3048)
			(end -0.67945 -0.3048)
			(stroke
				(width 0.1)
				(type default)
			)
			(layer "B.Fab")
		)
		(fp_line
			(start -0.67945 -0.3048)
			(end -0.67945 0.3048)
			(stroke
				(width 0.1)
				(type default)
			)
			(layer "B.Fab")
		)
		(fp_line
			(start 0.12065 -0.2794)
			(end -0.12065 -0.2794)
			(stroke
				(width 0.1)
				(type default)
			)
			(layer "B.Fab")
		)
		(fp_line
			(start -0.12065 -0.2794)
			(end -0.12065 -0.3048)
			(stroke
				(width 0.1)
				(type default)
			)
			(layer "B.Fab")
		)
		(fp_line
			(start 0.12065 0.2794)
			(end 0.12065 0.3048)
			(stroke
				(width 0.1)
				(type default)
			)
			(layer "B.Fab")
		)
		(fp_line
			(start -0.120396 0.2794)
			(end 0.12065 0.2794)
			(stroke
				(width 0.1)
				(type default)
			)
			(layer "B.Fab")
		)
		(fp_line
			(start 0.67945 0.3048)
			(end 0.67945 -0.305054)
			(stroke
				(width 0.1)
				(type default)
			)
			(layer "B.Fab")
		)
		(fp_line
			(start 0.12065 0.3048)
			(end 0.67945 0.3048)
			(stroke
				(width 0.1)
				(type default)
			)
			(layer "B.Fab")
		)
		(fp_line
			(start -0.120396 0.3048)
			(end -0.120396 0.2794)
			(stroke
				(width 0.1)
				(type default)
			)
			(layer "B.Fab")
		)
		(fp_line
			(start -0.67945 0.3048)
			(end -0.120396 0.3048)
			(stroke
				(width 0.1)
				(type default)
			)
			(layer "B.Fab")
		)
		(pad "1" smd circle
			(at 0.40005 0 270)
			(size 0 0)
			(layers "B.Cu" "B.Mask" "B.Paste")
			(net "M_BMC_DDR4_MBA0")
		)
		(pad "2" smd circle
			(at -0.40005 0 270)
			(size 0 0)
			(layers "B.Cu" "B.Mask" "B.Paste")
			(net "P1V2_AUX")
		)
	)
	(footprint ""
		(layer "B.Cu")
		(at 29.8196 -106.2482 -90)
		(property "Reference" "R77"
			(at 0 0 90)
			(layer "B.SilkS")
			(hide yes)
			(effects
				(font
					(size 1.27 1.27)
				)
				(justify mirror)
			)
		)
		(property "Value" ""
			(at 0 0 90)
			(layer "B.Fab")
			(effects
				(font
					(size 1.27 1.27)
				)
				(justify mirror)
			)
		)
		(duplicate_pad_numbers_are_jumpers no)
		(fp_line
			(start -0.7874 0.4064)
			(end 0.7874 0.4064)
			(stroke
				(width 0.1524)
				(type default)
			)
			(layer "B.SilkS")
		)
		(fp_line
			(start 0.7874 0.4064)
			(end 0.7874 -0.4064)
			(stroke
				(width 0.1524)
				(type default)
			)
			(layer "B.SilkS")
		)
		(fp_line
			(start -0.7874 -0.4064)
			(end -0.7874 0.4064)
			(stroke
				(width 0.1524)
				(type default)
			)
			(layer "B.SilkS")
		)
		(fp_line
			(start 0.7874 -0.4064)
			(end -0.7874 -0.4064)
			(stroke
				(width 0.1524)
				(type default)
			)
			(layer "B.SilkS")
		)
		(fp_line
			(start -0.67945 0.3048)
			(end -0.120396 0.3048)
			(stroke
				(width 0.1)
				(type default)
			)
			(layer "B.Fab")
		)
		(fp_line
			(start -0.120396 0.3048)
			(end -0.120396 0.2794)
			(stroke
				(width 0.1)
				(type default)
			)
			(layer "B.Fab")
		)
		(fp_line
			(start 0.12065 0.3048)
			(end 0.67945 0.3048)
			(stroke
				(width 0.1)
				(type default)
			)
			(layer "B.Fab")
		)
		(fp_line
			(start 0.67945 0.3048)
			(end 0.67945 -0.305054)
			(stroke
				(width 0.1)
				(type default)
			)
			(layer "B.Fab")
		)
		(fp_line
			(start -0.120396 0.2794)
			(end 0.12065 0.2794)
			(stroke
				(width 0.1)
				(type default)
			)
			(layer "B.Fab")
		)
		(fp_line
			(start 0.12065 0.2794)
			(end 0.12065 0.3048)
			(stroke
				(width 0.1)
				(type default)
			)
			(layer "B.Fab")
		)
		(fp_line
			(start -0.12065 -0.2794)
			(end -0.12065 -0.3048)
			(stroke
				(width 0.1)
				(type default)
			)
			(layer "B.Fab")
		)
		(fp_line
			(start 0.12065 -0.2794)
			(end -0.12065 -0.2794)
			(stroke
				(width 0.1)
				(type default)
			)
			(layer "B.Fab")
		)
		(fp_line
			(start -0.67945 -0.3048)
			(end -0.67945 0.3048)
			(stroke
				(width 0.1)
				(type default)
			)
			(layer "B.Fab")
		)
		(fp_line
			(start -0.12065 -0.3048)
			(end -0.67945 -0.3048)
			(stroke
				(width 0.1)
				(type default)
			)
			(layer "B.Fab")
		)
		(fp_line
			(start 0.12065 -0.305054)
			(end 0.12065 -0.2794)
			(stroke
				(width 0.1)
				(type default)
			)
			(layer "B.Fab")
		)
		(fp_line
			(start 0.67945 -0.305054)
			(end 0.12065 -0.305054)
			(stroke
				(width 0.1)
				(type default)
			)
			(layer "B.Fab")
		)
		(pad "1" smd circle
			(at 0.40005 0 90)
			(size 0 0)
			(layers "B.Cu" "B.Mask" "B.Paste")
			(net "P3V3_AUX")
		)
		(pad "2" smd circle
			(at -0.40005 0 90)
			(size 0 0)
			(layers "B.Cu" "B.Mask" "B.Paste")
			(net "SGPIO_LD_0")
		)
	)
)
